# T6G (Grand Teton) — schematic netlist excerpt (pin names and nets, part order shuffled) for the footprints in the layout excerpt that follows; sources: Cadence DE-HDL packaged netlist, KiCad conversion of 04192023_DAF0TMB3IC0_F0TG_MB_C_brd_V02_OCP.brd

J70  PICOPROBE_BXA  DELTA-L 4.0 EMPTY  pkg TRIANG_LAUNCH_3PXB  page 229
  \1_p\  = DELTA_L_85_5INCH_BOT_DN
  \2_n\  = DELTA_L_85_5INCH_BOT_DP
  \3_g\  = DELTA_L_GND_1

(kicad_pcb
	(version 20260206)
	(generator "pcbnew")
	(generator_version "10.0")
	(general
		(thickness 1.6)
		(legacy_teardrops no)
	)
	(paper "A4")
	(title_block
		(title "04192023_DAF0TMB3IC0_F0TG_MB_C_brd_V02_OCP.brd")
		(comment 1 "Grand Teton / footprints 5385-5385 of 8354")
	)
	(layers
		(0 "F.Cu" signal "TOP")
		(4 "In1.Cu" signal "GND")
		(6 "In2.Cu" signal "IN1")
		(8 "In3.Cu" signal "GND1")
		(10 "In4.Cu" signal "IN2")
		(12 "In5.Cu" signal "GND2")
		(14 "In6.Cu" signal "IN3")
		(16 "In7.Cu" signal "GND3")
		(18 "In8.Cu" signal "VCC")
		(20 "In9.Cu" signal "VCC1")
		(22 "In10.Cu" signal "GND4")
		(24 "In11.Cu" signal "IN4")
		(26 "In12.Cu" signal "GND5")
		(28 "In13.Cu" signal "IN5")
		(30 "In14.Cu" signal "GND6")
		(32 "In15.Cu" signal "IN6")
		(34 "In16.Cu" signal "GND7")
		(2 "B.Cu" signal "BOTTOM")
		(9 "F.Adhes" user "F.Adhesive")
		(11 "B.Adhes" user "B.Adhesive")
		(13 "F.Paste" user "Package Geometry/Pastemask Top")
		(15 "B.Paste" user "Package Geometry/Pastemask Bottom")
		(5 "F.SilkS" user "Ref Des/Silkscreen Top")
		(7 "B.SilkS" user "Ref Des/Silkscreen Bottom")
		(1 "F.Mask" user "Board Geometry/Soldermask Top")
		(3 "B.Mask" user "Board Geometry/Soldermask Bottom")
		(17 "Dwgs.User" user "User.Drawings")
		(19 "Cmts.User" user "User.Comments")
		(21 "Eco1.User" user "User.Eco1")
		(23 "Eco2.User" user "User.Eco2")
		(25 "Edge.Cuts" user "Board Geometry/Outline")
		(27 "Margin" user)
		(31 "F.CrtYd" user "Package Geometry/Place Bound Top")
		(29 "B.CrtYd" user "Package Geometry/Place Bound Bottom")
		(35 "F.Fab" user "Ref Des/Assembly Top")
		(33 "B.Fab" user "Ref Des/Assembly Bottom")
	)
	(footprint ""
		(layer "B.Cu")
		(at 314.965588 2.542794 180)
		(property "Reference" "J70"
			(at 4.55422 -0.940308 270)
			(unlocked yes)
			(layer "B.SilkS")
			(effects
				(font
					(size 0.7874 0.5842)
					(thickness 0.1524)
				)
				(justify left mirror)
			)
		)
		(property "Value" ""
			(at 0 0 0)
			(layer "B.Fab")
			(effects
				(font
					(size 1.27 1.27)
				)
				(justify mirror)
			)
		)
		(duplicate_pad_numbers_are_jumpers no)
		(fp_line
			(start 1.2192 2.06756)
			(end 1.2192 -2.06756)
			(stroke
				(width 0.1524)
				(type default)
			)
			(layer "B.SilkS")
		)
		(fp_line
			(start 1.2192 -2.06756)
			(end -1.2192 -2.06756)
			(stroke
				(width 0.1524)
				(type default)
			)
			(layer "B.SilkS")
		)
		(fp_line
			(start -1.2192 2.06756)
			(end 1.2192 2.06756)
			(stroke
				(width 0.1524)
				(type default)
			)
			(layer "B.SilkS")
		)
		(fp_line
			(start -1.2192 -2.06756)
			(end -1.2192 2.06756)
			(stroke
				(width 0.1524)
				(type default)
			)
			(layer "B.SilkS")
		)
		(pad "" np_thru_hole circle
			(at -3.4671 -1.27 90)
			(size 1.0414 1.0414)
			(drill 1.0414)
			(layers "*.Cu" "*.Mask")
			(clearance 0.381)
			(thermal_gap 0.381)
		)
		(pad "" np_thru_hole circle
			(at -3.4671 1.27 90)
			(size 1.0414 1.0414)
			(drill 1.0414)
			(layers "*.Cu" "*.Mask")
			(clearance 0.381)
			(thermal_gap 0.381)
		)
		(pad "" np_thru_hole circle
			(at 2.8829 -1.27 90)
			(size 1.0414 1.0414)
			(drill 1.0414)
			(layers "*.Cu" "*.Mask")
			(clearance 0.381)
			(thermal_gap 0.381)
		)
		(pad "" np_thru_hole circle
			(at 2.8829 1.27 90)
			(size 1.0414 1.0414)
			(drill 1.0414)
			(layers "*.Cu" "*.Mask")
			(clearance 0.381)
			(thermal_gap 0.381)
		)
		(pad "1" smd rect
			(at -0.8255 -0.249936 90)
			(size 0.3048 0.508)
			(layers "B.Cu" "B.Mask" "B.Paste")
			(net "DELTA_L_85_5INCH_BOT_DN")
		)
		(pad "2" smd rect
			(at -0.8255 0.249936 90)
			(size 0.3048 0.508)
			(layers "B.Cu" "B.Mask" "B.Paste")
			(net "DELTA_L_85_5INCH_BOT_DP")
		)
		(pad "3" smd circle
			(at 0 0)
			(size 0 0)
			(layers "B.Cu" "B.Mask" "B.Paste")
			(net "DELTA_L_GND_1")
		)
		(zone
			(layers "F.Cu" "B.Cu" "In1.Cu" "In2.Cu" "In3.Cu" "In4.Cu" "In5.Cu" "In6.Cu"
				"In7.Cu" "In8.Cu" "In9.Cu" "In10.Cu" "In11.Cu" "In12.Cu" "In13.Cu" "In14.Cu"
				"In15.Cu" "In16.Cu"
			)
			(hatch none 0.5)
			(connect_pads
				(clearance 0)
			)
			(min_thickness 0.25)
			(keepout
				(tracks not_allowed)
				(vias allowed)
				(pads allowed)
				(copperpour not_allowed)
				(footprints allowed)
			)
			(placement
				(enabled no)
				(sheetname "")
			)
			(fill
				(thermal_gap 0.5)
				(thermal_bridge_width 0.5)
				(island_removal_mode 0)
			)
			(polygon
				(pts
					(arc
						(start 313.009788 1.272794)
						(mid 311.155588 1.272794)
						(end 313.009788 1.272794)
					)
				)
			)
		)
		(zone
			(layers "F.Cu" "B.Cu" "In1.Cu" "In2.Cu" "In3.Cu" "In4.Cu" "In5.Cu" "In6.Cu"
				"In7.Cu" "In8.Cu" "In9.Cu" "In10.Cu" "In11.Cu" "In12.Cu" "In13.Cu" "In14.Cu"
				"In15.Cu" "In16.Cu"
			)
			(hatch none 0.5)
			(connect_pads
				(clearance 0)
			)
			(min_thickness 0.25)
			(keepout
				(tracks not_allowed)
				(vias allowed)
				(pads allowed)
				(copperpour not_allowed)
				(footprints allowed)
			)
			(placement
				(enabled no)
				(sheetname "")
			)
			(fill
				(thermal_gap 0.5)
				(thermal_bridge_width 0.5)
				(island_removal_mode 0)
			)
			(polygon
				(pts
					(arc
						(start 313.009788 3.812794)
						(mid 311.155588 3.812794)
						(end 313.009788 3.812794)
					)
				)
			)
		)
		(zone
			(layers "F.Cu" "B.Cu" "In1.Cu" "In2.Cu" "In3.Cu" "In4.Cu" "In5.Cu" "In6.Cu"
				"In7.Cu" "In8.Cu" "In9.Cu" "In10.Cu" "In11.Cu" "In12.Cu" "In13.Cu" "In14.Cu"
				"In15.Cu" "In16.Cu"
			)
			(hatch none 0.5)
			(connect_pads
				(clearance 0)
			)
			(min_thickness 0.25)
			(keepout
				(tracks not_allowed)
				(vias allowed)
				(pads allowed)
				(copperpour not_allowed)
				(footprints allowed)
			)
			(placement
				(enabled no)
				(sheetname "")
			)
			(fill
				(thermal_gap 0.5)
				(thermal_bridge_width 0.5)
				(island_removal_mode 0)
			)
			(polygon
				(pts
					(arc
						(start 319.359788 1.272794)
						(mid 317.505588 1.272794)
						(end 319.359788 1.272794)
					)
				)
			)
		)
		(zone
			(layers "F.Cu" "B.Cu" "In1.Cu" "In2.Cu" "In3.Cu" "In4.Cu" "In5.Cu" "In6.Cu"
				"In7.Cu" "In8.Cu" "In9.Cu" "In10.Cu" "In11.Cu" "In12.Cu" "In13.Cu" "In14.Cu"
				"In15.Cu" "In16.Cu"
			)
			(hatch none 0.5)
			(connect_pads
				(clearance 0)
			)
			(min_thickness 0.25)
			(keepout
				(tracks not_allowed)
				(vias allowed)
				(pads allowed)
				(copperpour not_allowed)
				(footprints allowed)
			)
			(placement
				(enabled no)
				(sheetname "")
			)
			(fill
				(thermal_gap 0.5)
				(thermal_bridge_width 0.5)
				(island_removal_mode 0)
			)
			(polygon
				(pts
					(arc
						(start 319.359788 3.812794)
						(mid 317.505588 3.812794)
						(end 319.359788 3.812794)
					)
				)
			)
		)
		(zone
			(layer "B.Cu")
			(hatch none 0.5)
			(connect_pads
				(clearance 0)
			)
			(min_thickness 0.25)
			(keepout
				(tracks not_allowed)
				(vias allowed)
				(pads allowed)
				(copperpour not_allowed)
				(footprints allowed)
			)
			(placement
				(enabled no)
				(sheetname "")
			)
			(fill
				(thermal_gap 0.5)
				(thermal_bridge_width 0.5)
				(island_removal_mode 0)
			)
			(polygon
				(pts
					(xy 316.083188 3.091434) (xy 316.083188 2.99593) (xy 315.486288 2.99593) (xy 315.486288 2.58953)
					(xy 316.083188 2.58953) (xy 316.083188 2.496058) (xy 315.486288 2.496058) (xy 315.486288 2.089658)
					(xy 316.083188 2.089658) (xy 316.083188 1.994154) (xy 315.384688 1.994154) (xy 315.384688 3.091434)
				)
			)
		)
	)
)
